(kicad_pcb
	(version 20260206)
	(generator "pcbnew")
	(generator_version "10.0")
	(general
		(thickness 1.6)
		(legacy_teardrops no)
	)
	(paper "A4")
	(title_block
		(title "04192023_DAF0TMB3IC0_F0TG_MB_C_brd_V02_OCP.brd")
		(comment 1 "Grand Teton / footprints 5831-5837 of 8354")
	)
	(layers
		(0 "F.Cu" signal "TOP")
		(4 "In1.Cu" signal "GND")
		(6 "In2.Cu" signal "IN1")
		(8 "In3.Cu" signal "GND1")
		(10 "In4.Cu" signal "IN2")
		(12 "In5.Cu" signal "GND2")
		(14 "In6.Cu" signal "IN3")
		(16 "In7.Cu" signal "GND3")
		(18 "In8.Cu" signal "VCC")
		(20 "In9.Cu" signal "VCC1")
		(22 "In10.Cu" signal "GND4")
		(24 "In11.Cu" signal "IN4")
		(26 "In12.Cu" signal "GND5")
		(28 "In13.Cu" signal "IN5")
		(30 "In14.Cu" signal "GND6")
		(32 "In15.Cu" signal "IN6")
		(34 "In16.Cu" signal "GND7")
		(2 "B.Cu" signal "BOTTOM")
		(9 "F.Adhes" user "F.Adhesive")
		(11 "B.Adhes" user "B.Adhesive")
		(13 "F.Paste" user "Package Geometry/Pastemask Top")
		(15 "B.Paste" user "Package Geometry/Pastemask Bottom")
		(5 "F.SilkS" user "Ref Des/Silkscreen Top")
		(7 "B.SilkS" user "Ref Des/Silkscreen Bottom")
		(1 "F.Mask" user "Board Geometry/Soldermask Top")
		(3 "B.Mask" user "Board Geometry/Soldermask Bottom")
		(17 "Dwgs.User" user "User.Drawings")
		(19 "Cmts.User" user "User.Comments")
		(21 "Eco1.User" user "User.Eco1")
		(23 "Eco2.User" user "User.Eco2")
		(25 "Edge.Cuts" user "Board Geometry/Outline")
		(27 "Margin" user)
		(31 "F.CrtYd" user "Package Geometry/Place Bound Top")
		(29 "B.CrtYd" user "Package Geometry/Place Bound Bottom")
		(35 "F.Fab" user "Ref Des/Assembly Top")
		(33 "B.Fab" user "Ref Des/Assembly Bottom")
	)
	(footprint ""
		(layer "B.Cu")
		(at 52.782978 -431.904902 -90)
		(property "Reference" "R3439"
			(at 0 0 90)
			(layer "B.SilkS")
			(hide yes)
			(effects
				(font
					(size 1.27 1.27)
				)
				(justify mirror)
			)
		)
		(property "Value" ""
			(at 0 0 90)
			(layer "B.Fab")
			(effects
				(font
					(size 1.27 1.27)
				)
				(justify mirror)
			)
		)
		(duplicate_pad_numbers_are_jumpers no)
		(fp_line
			(start -0.7874 0.4064)
			(end 0.7874 0.4064)
			(stroke
				(width 0.1524)
				(type default)
			)
			(layer "B.SilkS")
		)
		(fp_line
			(start 0.7874 0.4064)
			(end 0.7874 -0.4064)
			(stroke
				(width 0.1524)
				(type default)
			)
			(layer "B.SilkS")
		)
		(fp_line
			(start -0.7874 -0.4064)
			(end -0.7874 0.4064)
			(stroke
				(width 0.1524)
				(type default)
			)
			(layer "B.SilkS")
		)
		(fp_line
			(start 0.7874 -0.4064)
			(end -0.7874 -0.4064)
			(stroke
				(width 0.1524)
				(type default)
			)
			(layer "B.SilkS")
		)
		(fp_line
			(start -0.67945 0.3048)
			(end -0.120396 0.3048)
			(stroke
				(width 0.1)
				(type default)
			)
			(layer "B.Fab")
		)
		(fp_line
			(start -0.120396 0.3048)
			(end -0.120396 0.2794)
			(stroke
				(width 0.1)
				(type default)
			)
			(layer "B.Fab")
		)
		(fp_line
			(start 0.12065 0.3048)
			(end 0.67945 0.3048)
			(stroke
				(width 0.1)
				(type default)
			)
			(layer "B.Fab")
		)
		(fp_line
			(start 0.67945 0.3048)
			(end 0.67945 -0.305054)
			(stroke
				(width 0.1)
				(type default)
			)
			(layer "B.Fab")
		)
		(fp_line
			(start -0.120396 0.2794)
			(end 0.12065 0.2794)
			(stroke
				(width 0.1)
				(type default)
			)
			(layer "B.Fab")
		)
		(fp_line
			(start 0.12065 0.2794)
			(end 0.12065 0.3048)
			(stroke
				(width 0.1)
				(type default)
			)
			(layer "B.Fab")
		)
		(fp_line
			(start -0.12065 -0.2794)
			(end -0.12065 -0.3048)
			(stroke
				(width 0.1)
				(type default)
			)
			(layer "B.Fab")
		)
		(fp_line
			(start 0.12065 -0.2794)
			(end -0.12065 -0.2794)
			(stroke
				(width 0.1)
				(type default)
			)
			(layer "B.Fab")
		)
		(fp_line
			(start -0.67945 -0.3048)
			(end -0.67945 0.3048)
			(stroke
				(width 0.1)
				(type default)
			)
			(layer "B.Fab")
		)
		(fp_line
			(start -0.12065 -0.3048)
			(end -0.67945 -0.3048)
			(stroke
				(width 0.1)
				(type default)
			)
			(layer "B.Fab")
		)
		(fp_line
			(start 0.12065 -0.305054)
			(end 0.12065 -0.2794)
			(stroke
				(width 0.1)
				(type default)
			)
			(layer "B.Fab")
		)
		(fp_line
			(start 0.67945 -0.305054)
			(end 0.12065 -0.305054)
			(stroke
				(width 0.1)
				(type default)
			)
			(layer "B.Fab")
		)
		(pad "1" smd circle
			(at 0.40005 0 90)
			(size 0 0)
			(layers "B.Cu" "B.Mask" "B.Paste")
			(net "P3V3_AUX")
		)
		(pad "2" smd circle
			(at -0.40005 0 90)
			(size 0 0)
			(layers "B.Cu" "B.Mask" "B.Paste")
			(net "GPU_FPGA_THERM_OVERT_ISO_N")
		)
	)
	(footprint ""
		(layer "B.Cu")
		(at 176.3776 -13.762228 90)
		(property "Reference" "R4507"
			(at 0 0 90)
			(layer "B.SilkS")
			(hide yes)
			(effects
				(font
					(size 1.27 1.27)
				)
				(justify mirror)
			)
		)
		(property "Value" ""
			(at 0 0 90)
			(layer "B.Fab")
			(effects
				(font
					(size 1.27 1.27)
				)
				(justify mirror)
			)
		)
		(duplicate_pad_numbers_are_jumpers no)
		(fp_line
			(start 0.7874 -0.4064)
			(end -0.7874 -0.4064)
			(stroke
				(width 0.1524)
				(type default)
			)
			(layer "B.SilkS")
		)
		(fp_line
			(start -0.7874 -0.4064)
			(end -0.7874 0.4064)
			(stroke
				(width 0.1524)
				(type default)
			)
			(layer "B.SilkS")
		)
		(fp_line
			(start 0.7874 0.4064)
			(end 0.7874 -0.4064)
			(stroke
				(width 0.1524)
				(type default)
			)
			(layer "B.SilkS")
		)
		(fp_line
			(start -0.7874 0.4064)
			(end 0.7874 0.4064)
			(stroke
				(width 0.1524)
				(type default)
			)
			(layer "B.SilkS")
		)
		(fp_line
			(start 0.67945 -0.305054)
			(end 0.12065 -0.305054)
			(stroke
				(width 0.1)
				(type default)
			)
			(layer "B.Fab")
		)
		(fp_line
			(start 0.12065 -0.305054)
			(end 0.12065 -0.2794)
			(stroke
				(width 0.1)
				(type default)
			)
			(layer "B.Fab")
		)
		(fp_line
			(start -0.12065 -0.3048)
			(end -0.67945 -0.3048)
			(stroke
				(width 0.1)
				(type default)
			)
			(layer "B.Fab")
		)
		(fp_line
			(start -0.67945 -0.3048)
			(end -0.67945 0.3048)
			(stroke
				(width 0.1)
				(type default)
			)
			(layer "B.Fab")
		)
		(fp_line
			(start 0.12065 -0.2794)
			(end -0.12065 -0.2794)
			(stroke
				(width 0.1)
				(type default)
			)
			(layer "B.Fab")
		)
		(fp_line
			(start -0.12065 -0.2794)
			(end -0.12065 -0.3048)
			(stroke
				(width 0.1)
				(type default)
			)
			(layer "B.Fab")
		)
		(fp_line
			(start 0.12065 0.2794)
			(end 0.12065 0.3048)
			(stroke
				(width 0.1)
				(type default)
			)
			(layer "B.Fab")
		)
		(fp_line
			(start -0.120396 0.2794)
			(end 0.12065 0.2794)
			(stroke
				(width 0.1)
				(type default)
			)
			(layer "B.Fab")
		)
		(fp_line
			(start 0.67945 0.3048)
			(end 0.67945 -0.305054)
			(stroke
				(width 0.1)
				(type default)
			)
			(layer "B.Fab")
		)
		(fp_line
			(start 0.12065 0.3048)
			(end 0.67945 0.3048)
			(stroke
				(width 0.1)
				(type default)
			)
			(layer "B.Fab")
		)
		(fp_line
			(start -0.120396 0.3048)
			(end -0.120396 0.2794)
			(stroke
				(width 0.1)
				(type default)
			)
			(layer "B.Fab")
		)
		(fp_line
			(start -0.67945 0.3048)
			(end -0.120396 0.3048)
			(stroke
				(width 0.1)
				(type default)
			)
			(layer "B.Fab")
		)
		(pad "1" smd circle
			(at 0.40005 0 270)
			(size 0 0)
			(layers "B.Cu" "B.Mask" "B.Paste")
			(net "SMB_CPU0_CPU1_SEC_SDA")
		)
		(pad "2" smd circle
			(at -0.40005 0 270)
			(size 0 0)
			(layers "B.Cu" "B.Mask" "B.Paste")
			(net "SMB_CPU0_CPU1_SEC_SDA_R")
		)
	)
	(footprint ""
		(layer "B.Cu")
		(at 63.385954 -177.349912 90)
		(property "Reference" "PC316_5"
			(at 0 0 90)
			(layer "B.SilkS")
			(hide yes)
			(effects
				(font
					(size 1.27 1.27)
				)
				(justify mirror)
			)
		)
		(property "Value" ""
			(at 0 0 90)
			(layer "B.Fab")
			(effects
				(font
					(size 1.27 1.27)
				)
				(justify mirror)
			)
		)
		(duplicate_pad_numbers_are_jumpers no)
		(fp_line
			(start 1.524 -0.762)
			(end -1.524 -0.762)
			(stroke
				(width 0.1524)
				(type default)
			)
			(layer "B.SilkS")
		)
		(fp_line
			(start -1.524 -0.762)
			(end -1.524 0.762)
			(stroke
				(width 0.1524)
				(type default)
			)
			(layer "B.SilkS")
		)
		(fp_line
			(start 1.524 0.762)
			(end 1.524 -0.762)
			(stroke
				(width 0.1524)
				(type default)
			)
			(layer "B.SilkS")
		)
		(fp_line
			(start -1.524 0.762)
			(end 1.524 0.762)
			(stroke
				(width 0.1524)
				(type default)
			)
			(layer "B.SilkS")
		)
		(fp_line
			(start 1.1049 -0.724916)
			(end 1.1049 0.724916)
			(stroke
				(width 0.1)
				(type default)
			)
			(layer "B.Fab")
		)
		(fp_line
			(start -1.1049 -0.724916)
			(end 1.1049 -0.724916)
			(stroke
				(width 0.1)
				(type default)
			)
			(layer "B.Fab")
		)
		(fp_line
			(start 1.1049 0.724916)
			(end -1.1049 0.724916)
			(stroke
				(width 0.1)
				(type default)
			)
			(layer "B.Fab")
		)
		(fp_line
			(start -1.1049 0.724916)
			(end -1.1049 -0.724916)
			(stroke
				(width 0.1)
				(type default)
			)
			(layer "B.Fab")
		)
		(pad "1" smd rect
			(at 0.889 0 90)
			(size 1.016 1.27)
			(layers "B.Cu" "B.Mask" "B.Paste")
			(net "PVDDCR_CPU0_P1")
		)
		(pad "2" smd rect
			(at -0.889 0 90)
			(size 1.016 1.27)
			(layers "B.Cu" "B.Mask" "B.Paste")
			(net "GND")
		)
	)
	(footprint ""
		(layer "B.Cu")
		(at 398.893538 -393.04468 180)
		(property "Reference" "R1076"
			(at 0 0 0)
			(layer "B.SilkS")
			(hide yes)
			(effects
				(font
					(size 1.27 1.27)
				)
				(justify mirror)
			)
		)
		(property "Value" ""
			(at 0 0 0)
			(layer "B.Fab")
			(effects
				(font
					(size 1.27 1.27)
				)
				(justify mirror)
			)
		)
		(duplicate_pad_numbers_are_jumpers no)
		(fp_line
			(start 0.32512 0.175006)
			(end 0.32512 -0.175006)
			(stroke
				(width 0.1)
				(type default)
			)
			(layer "B.Fab")
		)
		(fp_line
			(start 0.32512 -0.175006)
			(end -0.32512 -0.175006)
			(stroke
				(width 0.1)
				(type default)
			)
			(layer "B.Fab")
		)
		(fp_line
			(start -0.32512 0.175006)
			(end 0.32512 0.175006)
			(stroke
				(width 0.1)
				(type default)
			)
			(layer "B.Fab")
		)
		(fp_line
			(start -0.32512 -0.175006)
			(end -0.32512 0.175006)
			(stroke
				(width 0.1)
				(type default)
			)
			(layer "B.Fab")
		)
		(pad "1" smd rect
			(at 0.2667 0)
			(size 0.3048 0.381)
			(layers "B.Cu" "B.Mask" "B.Paste")
			(net "TEST1_RT_CPU0_P2")
		)
		(pad "2" smd rect
			(at -0.2667 0 180)
			(size 0.3048 0.381)
			(layers "B.Cu" "B.Mask" "B.Paste")
			(net "GND")
		)
	)
	(footprint ""
		(layer "B.Cu")
		(at 396.168372 -395.127988 -90)
		(property "Reference" "C994"
			(at 0 0 90)
			(layer "B.SilkS")
			(hide yes)
			(effects
				(font
					(size 1.27 1.27)
				)
				(justify mirror)
			)
		)
		(property "Value" ""
			(at 0 0 90)
			(layer "B.Fab")
			(effects
				(font
					(size 1.27 1.27)
				)
				(justify mirror)
			)
		)
		(duplicate_pad_numbers_are_jumpers no)
		(fp_line
			(start -0.7874 0.4064)
			(end 0.7874 0.4064)
			(stroke
				(width 0.1524)
				(type default)
			)
			(layer "B.SilkS")
		)
		(fp_line
			(start 0.7874 0.4064)
			(end 0.7874 -0.4064)
			(stroke
				(width 0.1524)
				(type default)
			)
			(layer "B.SilkS")
		)
		(fp_line
			(start -0.7874 -0.4064)
			(end -0.7874 0.4064)
			(stroke
				(width 0.1524)
				(type default)
			)
			(layer "B.SilkS")
		)
		(fp_line
			(start 0.7874 -0.4064)
			(end -0.7874 -0.4064)
			(stroke
				(width 0.1524)
				(type default)
			)
			(layer "B.SilkS")
		)
		(fp_line
			(start -0.67945 0.3048)
			(end -0.120396 0.3048)
			(stroke
				(width 0.1)
				(type default)
			)
			(layer "B.Fab")
		)
		(fp_line
			(start -0.120396 0.3048)
			(end -0.120396 0.2794)
			(stroke
				(width 0.1)
				(type default)
			)
			(layer "B.Fab")
		)
		(fp_line
			(start 0.12065 0.3048)
			(end 0.67945 0.3048)
			(stroke
				(width 0.1)
				(type default)
			)
			(layer "B.Fab")
		)
		(fp_line
			(start 0.67945 0.3048)
			(end 0.67945 -0.305054)
			(stroke
				(width 0.1)
				(type default)
			)
			(layer "B.Fab")
		)
		(fp_line
			(start -0.120396 0.2794)
			(end 0.12065 0.2794)
			(stroke
				(width 0.1)
				(type default)
			)
			(layer "B.Fab")
		)
		(fp_line
			(start 0.12065 0.2794)
			(end 0.12065 0.3048)
			(stroke
				(width 0.1)
				(type default)
			)
			(layer "B.Fab")
		)
		(fp_line
			(start -0.12065 -0.2794)
			(end -0.12065 -0.3048)
			(stroke
				(width 0.1)
				(type default)
			)
			(layer "B.Fab")
		)
		(fp_line
			(start 0.12065 -0.2794)
			(end -0.12065 -0.2794)
			(stroke
				(width 0.1)
				(type default)
			)
			(layer "B.Fab")
		)
		(fp_line
			(start -0.67945 -0.3048)
			(end -0.67945 0.3048)
			(stroke
				(width 0.1)
				(type default)
			)
			(layer "B.Fab")
		)
		(fp_line
			(start -0.12065 -0.3048)
			(end -0.67945 -0.3048)
			(stroke
				(width 0.1)
				(type default)
			)
			(layer "B.Fab")
		)
		(fp_line
			(start 0.12065 -0.305054)
			(end 0.12065 -0.2794)
			(stroke
				(width 0.1)
				(type default)
			)
			(layer "B.Fab")
		)
		(fp_line
			(start 0.67945 -0.305054)
			(end 0.12065 -0.305054)
			(stroke
				(width 0.1)
				(type default)
			)
			(layer "B.Fab")
		)
		(pad "1" smd circle
			(at 0.40005 0 90)
			(size 0 0)
			(layers "B.Cu" "B.Mask" "B.Paste")
			(net "P1V8_CPU0_RT_1D")
		)
		(pad "2" smd circle
			(at -0.40005 0 90)
			(size 0 0)
			(layers "B.Cu" "B.Mask" "B.Paste")
			(net "GND")
		)
	)
	(footprint ""
		(layer "B.Cu")
		(at 191.271144 -77.27823 -90)
		(property "Reference" "R3237"
			(at 0 0 90)
			(layer "B.SilkS")
			(hide yes)
			(effects
				(font
					(size 1.27 1.27)
				)
				(justify mirror)
			)
		)
		(property "Value" ""
			(at 0 0 90)
			(layer "B.Fab")
			(effects
				(font
					(size 1.27 1.27)
				)
				(justify mirror)
			)
		)
		(duplicate_pad_numbers_are_jumpers no)
		(fp_line
			(start -0.7874 0.4064)
			(end 0.7874 0.4064)
			(stroke
				(width 0.1524)
				(type default)
			)
			(layer "B.SilkS")
		)
		(fp_line
			(start 0.7874 0.4064)
			(end 0.7874 -0.4064)
			(stroke
				(width 0.1524)
				(type default)
			)
			(layer "B.SilkS")
		)
		(fp_line
			(start -0.7874 -0.4064)
			(end -0.7874 0.4064)
			(stroke
				(width 0.1524)
				(type default)
			)
			(layer "B.SilkS")
		)
		(fp_line
			(start 0.7874 -0.4064)
			(end -0.7874 -0.4064)
			(stroke
				(width 0.1524)
				(type default)
			)
			(layer "B.SilkS")
		)
		(fp_line
			(start -0.67945 0.3048)
			(end -0.120396 0.3048)
			(stroke
				(width 0.1)
				(type default)
			)
			(layer "B.Fab")
		)
		(fp_line
			(start -0.120396 0.3048)
			(end -0.120396 0.2794)
			(stroke
				(width 0.1)
				(type default)
			)
			(layer "B.Fab")
		)
		(fp_line
			(start 0.12065 0.3048)
			(end 0.67945 0.3048)
			(stroke
				(width 0.1)
				(type default)
			)
			(layer "B.Fab")
		)
		(fp_line
			(start 0.67945 0.3048)
			(end 0.67945 -0.305054)
			(stroke
				(width 0.1)
				(type default)
			)
			(layer "B.Fab")
		)
		(fp_line
			(start -0.120396 0.2794)
			(end 0.12065 0.2794)
			(stroke
				(width 0.1)
				(type default)
			)
			(layer "B.Fab")
		)
		(fp_line
			(start 0.12065 0.2794)
			(end 0.12065 0.3048)
			(stroke
				(width 0.1)
				(type default)
			)
			(layer "B.Fab")
		)
		(fp_line
			(start -0.12065 -0.2794)
			(end -0.12065 -0.3048)
			(stroke
				(width 0.1)
				(type default)
			)
			(layer "B.Fab")
		)
		(fp_line
			(start 0.12065 -0.2794)
			(end -0.12065 -0.2794)
			(stroke
				(width 0.1)
				(type default)
			)
			(layer "B.Fab")
		)
		(fp_line
			(start -0.67945 -0.3048)
			(end -0.67945 0.3048)
			(stroke
				(width 0.1)
				(type default)
			)
			(layer "B.Fab")
		)
		(fp_line
			(start -0.12065 -0.3048)
			(end -0.67945 -0.3048)
			(stroke
				(width 0.1)
				(type default)
			)
			(layer "B.Fab")
		)
		(fp_line
			(start 0.12065 -0.305054)
			(end 0.12065 -0.2794)
			(stroke
				(width 0.1)
				(type default)
			)
			(layer "B.Fab")
		)
		(fp_line
			(start 0.67945 -0.305054)
			(end 0.12065 -0.305054)
			(stroke
				(width 0.1)
				(type default)
			)
			(layer "B.Fab")
		)
		(pad "1" smd circle
			(at 0.40005 0 90)
			(size 0 0)
			(layers "B.Cu" "B.Mask" "B.Paste")
			(net "OCP_SFF_RBT_ARB_OUT")
		)
		(pad "2" smd circle
			(at -0.40005 0 90)
			(size 0 0)
			(layers "B.Cu" "B.Mask" "B.Paste")
			(net "OCP_SFF_RBT_ARB_IN_R")
		)
	)
	(footprint ""
		(layer "B.Cu")
		(at 115.864386 -264.354564)
		(property "Reference" "C2496"
			(at 0 0 0)
			(layer "B.SilkS")
			(hide yes)
			(effects
				(font
					(size 1.27 1.27)
				)
				(justify mirror)
			)
		)
		(property "Value" ""
			(at 0 0 0)
			(layer "B.Fab")
			(effects
				(font
					(size 1.27 1.27)
				)
				(justify mirror)
			)
		)
		(duplicate_pad_numbers_are_jumpers no)
		(fp_line
			(start -0.7874 -0.4064)
			(end -0.7874 0.4064)
			(stroke
				(width 0.1524)
				(type default)
			)
			(layer "B.SilkS")
		)
		(fp_line
			(start -0.7874 0.4064)
			(end 0.7874 0.4064)
			(stroke
				(width 0.1524)
				(type default)
			)
			(layer "B.SilkS")
		)
		(fp_line
			(start 0.7874 -0.4064)
			(end -0.7874 -0.4064)
			(stroke
				(width 0.1524)
				(type default)
			)
			(layer "B.SilkS")
		)
		(fp_line
			(start 0.7874 0.4064)
			(end 0.7874 -0.4064)
			(stroke
				(width 0.1524)
				(type default)
			)
			(layer "B.SilkS")
		)
		(fp_line
			(start -0.67945 -0.3048)
			(end -0.67945 0.3048)
			(stroke
				(width 0.1)
				(type default)
			)
			(layer "B.Fab")
		)
		(fp_line
			(start -0.67945 0.3048)
			(end -0.120396 0.3048)
			(stroke
				(width 0.1)
				(type default)
			)
			(layer "B.Fab")
		)
		(fp_line
			(start -0.12065 -0.3048)
			(end -0.67945 -0.3048)
			(stroke
				(width 0.1)
				(type default)
			)
			(layer "B.Fab")
		)
		(fp_line
			(start -0.12065 -0.2794)
			(end -0.12065 -0.3048)
			(stroke
				(width 0.1)
				(type default)
			)
			(layer "B.Fab")
		)
		(fp_line
			(start -0.120396 0.2794)
			(end 0.12065 0.2794)
			(stroke
				(width 0.1)
				(type default)
			)
			(layer "B.Fab")
		)
		(fp_line
			(start -0.120396 0.3048)
			(end -0.120396 0.2794)
			(stroke
				(width 0.1)
				(type default)
			)
			(layer "B.Fab")
		)
		(fp_line
			(start 0.12065 -0.305054)
			(end 0.12065 -0.2794)
			(stroke
				(width 0.1)
				(type default)
			)
			(layer "B.Fab")
		)
		(fp_line
			(start 0.12065 -0.2794)
			(end -0.12065 -0.2794)
			(stroke
				(width 0.1)
				(type default)
			)
			(layer "B.Fab")
		)
		(fp_line
			(start 0.12065 0.2794)
			(end 0.12065 0.3048)
			(stroke
				(width 0.1)
				(type default)
			)
			(layer "B.Fab")
		)
		(fp_line
			(start 0.12065 0.3048)
			(end 0.67945 0.3048)
			(stroke
				(width 0.1)
				(type default)
			)
			(layer "B.Fab")
		)
		(fp_line
			(start 0.67945 -0.305054)
			(end 0.12065 -0.305054)
			(stroke
				(width 0.1)
				(type default)
			)
			(layer "B.Fab")
		)
		(fp_line
			(start 0.67945 0.3048)
			(end 0.67945 -0.305054)
			(stroke
				(width 0.1)
				(type default)
			)
			(layer "B.Fab")
		)
		(pad "1" smd circle
			(at 0.40005 0 180)
			(size 0 0)
			(layers "B.Cu" "B.Mask" "B.Paste")
			(net "PVDD11_S3_P1")
		)
		(pad "2" smd circle
			(at -0.40005 0 180)
			(size 0 0)
			(layers "B.Cu" "B.Mask" "B.Paste")
			(net "GND")
		)
	)
)
